#ISCELL
  mstr_misc dns *
  *
#ISCELL
  mstr_symbols bom_note *
  *
#ISCELL
  mstr_symbols cad_note *
  *
#ISCELL
  mstr_symbols intel_corp_bpage *
  *
#ISCELL
  mstr_symbols p3v3_stby *
  page162_i10
#CELL
  mstr_discrete res *
  page162_i13
#ISCELL
  mstr_standard offpage *
  page162_i16
#ISCELL
  mstr_standard offpage *
  page162_i17
#ISCELL
  mstr_standard offpage *
  page162_i19
#ISCELL
  mstr_standard offpage *
  page162_i21
#CELL
  mstr_discrete res *
  page162_i22
#CELL
  mstr_discrete res *
  page162_i23
#CELL
  mstr_discrete res *
  page162_i24
#CELL
  dev_discrete cap_a *
  page162_i28
#CELL
  dev_discrete cap_a *
  page162_i30
#ISCELL
  mstr_symbols gnd *
  page162_i31
#CELL
  mstr_memory w25q128 *
  page162_i32
#ISCELL
  mstr_symbols gnd *
  page162_i33
#ISCELL
  mstr_symbols gnd *
  page162_i6
#CELL
  mstr_discrete res *
  page162_i8
#CELL
  mstr_discrete res *
  page162_i9
